# T6G (Grand Teton) — schematic netlist excerpt (pin names and nets, part order shuffled) for the footprints in the layout excerpt that follows; sources: Cadence DE-HDL packaged netlist, KiCad conversion of 04192023_DAF0TMB3IC0_F0TG_MB_C_brd_V02_OCP.brd

C7027  Q_CAPP  470UF 2.5V 20% SPCAP  pkg SMLF  page 345 : A = P0V9_CPU1_RT2_2A ; B = GND
C144  Q_CAP  0.1UF 25V 10% X7R  pkg 0402  page 100 : A = P3V3_AUX ; B = GND

(kicad_pcb
	(version 20260206)
	(generator "pcbnew")
	(generator_version "10.0")
	(general
		(thickness 1.6)
		(legacy_teardrops no)
	)
	(paper "A4")
	(title_block
		(title "04192023_DAF0TMB3IC0_F0TG_MB_C_brd_V02_OCP.brd")
		(comment 1 "Grand Teton / footprints 5782-5783 of 8354")
	)
	(layers
		(0 "F.Cu" signal "TOP")
		(4 "In1.Cu" signal "GND")
		(6 "In2.Cu" signal "IN1")
		(8 "In3.Cu" signal "GND1")
		(10 "In4.Cu" signal "IN2")
		(12 "In5.Cu" signal "GND2")
		(14 "In6.Cu" signal "IN3")
		(16 "In7.Cu" signal "GND3")
		(18 "In8.Cu" signal "VCC")
		(20 "In9.Cu" signal "VCC1")
		(22 "In10.Cu" signal "GND4")
		(24 "In11.Cu" signal "IN4")
		(26 "In12.Cu" signal "GND5")
		(28 "In13.Cu" signal "IN5")
		(30 "In14.Cu" signal "GND6")
		(32 "In15.Cu" signal "IN6")
		(34 "In16.Cu" signal "GND7")
		(2 "B.Cu" signal "BOTTOM")
		(9 "F.Adhes" user "F.Adhesive")
		(11 "B.Adhes" user "B.Adhesive")
		(13 "F.Paste" user "Package Geometry/Pastemask Top")
		(15 "B.Paste" user "Package Geometry/Pastemask Bottom")
		(5 "F.SilkS" user "Ref Des/Silkscreen Top")
		(7 "B.SilkS" user "Ref Des/Silkscreen Bottom")
		(1 "F.Mask" user "Board Geometry/Soldermask Top")
		(3 "B.Mask" user "Board Geometry/Soldermask Bottom")
		(17 "Dwgs.User" user "User.Drawings")
		(19 "Cmts.User" user "User.Comments")
		(21 "Eco1.User" user "User.Eco1")
		(23 "Eco2.User" user "User.Eco2")
		(25 "Edge.Cuts" user "Board Geometry/Outline")
		(27 "Margin" user)
		(31 "F.CrtYd" user "Package Geometry/Place Bound Top")
		(29 "B.CrtYd" user "Package Geometry/Place Bound Bottom")
		(35 "F.Fab" user "Ref Des/Assembly Top")
		(33 "B.Fab" user "Ref Des/Assembly Bottom")
	)
	(footprint ""
		(layer "B.Cu")
		(at 43.576748 -193.971164)
		(property "Reference" "C144"
			(at 0 0 0)
			(layer "B.SilkS")
			(hide yes)
			(effects
				(font
					(size 1.27 1.27)
				)
				(justify mirror)
			)
		)
		(property "Value" ""
			(at 0 0 0)
			(layer "B.Fab")
			(effects
				(font
					(size 1.27 1.27)
				)
				(justify mirror)
			)
		)
		(duplicate_pad_numbers_are_jumpers no)
		(fp_line
			(start -0.7874 -0.4064)
			(end -0.7874 0.4064)
			(stroke
				(width 0.1524)
				(type default)
			)
			(layer "B.SilkS")
		)
		(fp_line
			(start -0.7874 0.4064)
			(end 0.7874 0.4064)
			(stroke
				(width 0.1524)
				(type default)
			)
			(layer "B.SilkS")
		)
		(fp_line
			(start 0.7874 -0.4064)
			(end -0.7874 -0.4064)
			(stroke
				(width 0.1524)
				(type default)
			)
			(layer "B.SilkS")
		)
		(fp_line
			(start 0.7874 0.4064)
			(end 0.7874 -0.4064)
			(stroke
				(width 0.1524)
				(type default)
			)
			(layer "B.SilkS")
		)
		(fp_line
			(start -0.67945 -0.3048)
			(end -0.67945 0.3048)
			(stroke
				(width 0.1)
				(type default)
			)
			(layer "B.Fab")
		)
		(fp_line
			(start -0.67945 0.3048)
			(end -0.120396 0.3048)
			(stroke
				(width 0.1)
				(type default)
			)
			(layer "B.Fab")
		)
		(fp_line
			(start -0.12065 -0.3048)
			(end -0.67945 -0.3048)
			(stroke
				(width 0.1)
				(type default)
			)
			(layer "B.Fab")
		)
		(fp_line
			(start -0.12065 -0.2794)
			(end -0.12065 -0.3048)
			(stroke
				(width 0.1)
				(type default)
			)
			(layer "B.Fab")
		)
		(fp_line
			(start -0.120396 0.2794)
			(end 0.12065 0.2794)
			(stroke
				(width 0.1)
				(type default)
			)
			(layer "B.Fab")
		)
		(fp_line
			(start -0.120396 0.3048)
			(end -0.120396 0.2794)
			(stroke
				(width 0.1)
				(type default)
			)
			(layer "B.Fab")
		)
		(fp_line
			(start 0.12065 -0.305054)
			(end 0.12065 -0.2794)
			(stroke
				(width 0.1)
				(type default)
			)
			(layer "B.Fab")
		)
		(fp_line
			(start 0.12065 -0.2794)
			(end -0.12065 -0.2794)
			(stroke
				(width 0.1)
				(type default)
			)
			(layer "B.Fab")
		)
		(fp_line
			(start 0.12065 0.2794)
			(end 0.12065 0.3048)
			(stroke
				(width 0.1)
				(type default)
			)
			(layer "B.Fab")
		)
		(fp_line
			(start 0.12065 0.3048)
			(end 0.67945 0.3048)
			(stroke
				(width 0.1)
				(type default)
			)
			(layer "B.Fab")
		)
		(fp_line
			(start 0.67945 -0.305054)
			(end 0.12065 -0.305054)
			(stroke
				(width 0.1)
				(type default)
			)
			(layer "B.Fab")
		)
		(fp_line
			(start 0.67945 0.3048)
			(end 0.67945 -0.305054)
			(stroke
				(width 0.1)
				(type default)
			)
			(layer "B.Fab")
		)
		(pad "1" smd circle
			(at 0.40005 0 180)
			(size 0 0)
			(layers "B.Cu" "B.Mask" "B.Paste")
			(net "P3V3_AUX")
		)
		(pad "2" smd circle
			(at -0.40005 0 180)
			(size 0 0)
			(layers "B.Cu" "B.Mask" "B.Paste")
			(net "GND")
		)
	)
	(footprint ""
		(layer "B.Cu")
		(at 152.124918 -381.11303 180)
		(property "Reference" "C7027"
			(at -1.683004 -3.177032 0)
			(unlocked yes)
			(layer "B.SilkS")
			(effects
				(font
					(size 0.7874 0.5842)
					(thickness 0.1524)
				)
				(justify left mirror)
			)
		)
		(property "Value" ""
			(at 0 0 0)
			(layer "B.Fab")
			(effects
				(font
					(size 1.27 1.27)
				)
				(justify mirror)
			)
		)
		(duplicate_pad_numbers_are_jumpers no)
		(fp_line
			(start 4.84378 -2.150618)
			(end 4.842256 2.163064)
			(stroke
				(width 0.1524)
				(type default)
			)
			(layer "B.SilkS")
		)
		(fp_line
			(start 4.84378 -2.150618)
			(end 4.53898 -2.150618)
			(stroke
				(width 0.1524)
				(type default)
			)
			(layer "B.SilkS")
		)
		(fp_line
			(start 4.83108 2.150364)
			(end 4.447794 2.149348)
			(stroke
				(width 0.1524)
				(type default)
			)
			(layer "B.SilkS")
		)
		(fp_line
			(start 4.69138 -2.150618)
			(end 4.692396 2.161032)
			(stroke
				(width 0.1524)
				(type default)
			)
			(layer "B.SilkS")
		)
		(fp_line
			(start 4.53898 2.15011)
			(end 4.53898 -2.15011)
			(stroke
				(width 0.1524)
				(type default)
			)
			(layer "B.SilkS")
		)
		(fp_line
			(start 4.53898 -2.15011)
			(end -4.53898 -2.15011)
			(stroke
				(width 0.1524)
				(type default)
			)
			(layer "B.SilkS")
		)
		(fp_line
			(start 4.53898 -2.150618)
			(end 4.539742 2.152142)
			(stroke
				(width 0.1524)
				(type default)
			)
			(layer "B.SilkS")
		)
		(fp_line
			(start -4.53898 2.15011)
			(end 4.53898 2.15011)
			(stroke
				(width 0.1524)
				(type default)
			)
			(layer "B.SilkS")
		)
		(fp_line
			(start -4.53898 -2.15011)
			(end -4.53898 2.15011)
			(stroke
				(width 0.1524)
				(type default)
			)
			(layer "B.SilkS")
		)
		(fp_line
			(start 3.64998 2.15011)
			(end 3.64998 -2.15011)
			(stroke
				(width 0.1)
				(type default)
			)
			(layer "B.Fab")
		)
		(fp_line
			(start 3.64998 -2.15011)
			(end -3.64998 -2.15011)
			(stroke
				(width 0.1)
				(type default)
			)
			(layer "B.Fab")
		)
		(fp_line
			(start -3.64998 2.15011)
			(end 3.64998 2.15011)
			(stroke
				(width 0.1)
				(type default)
			)
			(layer "B.Fab")
		)
		(fp_line
			(start -3.64998 -2.15011)
			(end -3.64998 2.15011)
			(stroke
				(width 0.1)
				(type default)
			)
			(layer "B.Fab")
		)
		(fp_text user "+"
			(at 4.185412 -3.072638 180)
			(unlocked yes)
			(layer "B.SilkS")
			(effects
				(font
					(size 1.905 1.4224)
					(thickness 0.1524)
				)
				(justify left mirror)
			)
		)
		(fp_text user "-"
			(at -2.944114 -2.830068 180)
			(unlocked yes)
			(layer "B.SilkS")
			(effects
				(font
					(size 1.905 1.4224)
					(thickness 0.1524)
				)
				(justify left mirror)
			)
		)
		(fp_text user "+"
			(at 6.214872 -0.337058 180)
			(unlocked yes)
			(layer "B.Fab")
			(effects
				(font
					(size 1.905 1.4224)
					(thickness 0.1524)
				)
				(justify left mirror)
			)
		)
		(fp_text user "-"
			(at -4.313174 -0.094488 180)
			(unlocked yes)
			(layer "B.Fab")
			(effects
				(font
					(size 1.905 1.4224)
					(thickness 0.1524)
				)
				(justify left mirror)
			)
		)
		(pad "1" smd rect
			(at 3.199892 0)
			(size 2.413 2.8194)
			(layers "B.Cu" "B.Mask" "B.Paste")
			(net "P0V9_CPU1_RT2_2A")
		)
		(pad "2" smd rect
			(at -3.199892 0)
			(size 2.413 2.8194)
			(layers "B.Cu" "B.Mask" "B.Paste")
			(net "GND")
		)
	)
)
